(kicad_pcb
	(version 20260206)
	(generator "pcbnew")
	(generator_version "10.0")
	(general
		(thickness 1.6)
		(legacy_teardrops no)
	)
	(paper "A4")
	(title_block
		(title "04192023_DAF0TMB3IC0_F0TG_MB_C_brd_V02_OCP.brd")
		(comment 1 "Grand Teton / footprints 3621-3627 of 8354")
	)
	(layers
		(0 "F.Cu" signal "TOP")
		(4 "In1.Cu" signal "GND")
		(6 "In2.Cu" signal "IN1")
		(8 "In3.Cu" signal "GND1")
		(10 "In4.Cu" signal "IN2")
		(12 "In5.Cu" signal "GND2")
		(14 "In6.Cu" signal "IN3")
		(16 "In7.Cu" signal "GND3")
		(18 "In8.Cu" signal "VCC")
		(20 "In9.Cu" signal "VCC1")
		(22 "In10.Cu" signal "GND4")
		(24 "In11.Cu" signal "IN4")
		(26 "In12.Cu" signal "GND5")
		(28 "In13.Cu" signal "IN5")
		(30 "In14.Cu" signal "GND6")
		(32 "In15.Cu" signal "IN6")
		(34 "In16.Cu" signal "GND7")
		(2 "B.Cu" signal "BOTTOM")
		(9 "F.Adhes" user "F.Adhesive")
		(11 "B.Adhes" user "B.Adhesive")
		(13 "F.Paste" user "Package Geometry/Pastemask Top")
		(15 "B.Paste" user "Package Geometry/Pastemask Bottom")
		(5 "F.SilkS" user "Ref Des/Silkscreen Top")
		(7 "B.SilkS" user "Ref Des/Silkscreen Bottom")
		(1 "F.Mask" user "Board Geometry/Soldermask Top")
		(3 "B.Mask" user "Board Geometry/Soldermask Bottom")
		(17 "Dwgs.User" user "User.Drawings")
		(19 "Cmts.User" user "User.Comments")
		(21 "Eco1.User" user "User.Eco1")
		(23 "Eco2.User" user "User.Eco2")
		(25 "Edge.Cuts" user "Board Geometry/Outline")
		(27 "Margin" user)
		(31 "F.CrtYd" user "Package Geometry/Place Bound Top")
		(29 "B.CrtYd" user "Package Geometry/Place Bound Bottom")
		(35 "F.Fab" user "Ref Des/Assembly Top")
		(33 "B.Fab" user "Ref Des/Assembly Bottom")
	)
	(footprint ""
		(layer "F.Cu")
		(at 256.889504 -44.520612 180)
		(property "Reference" "PC2207"
			(at 0 0 180)
			(layer "F.SilkS")
			(hide yes)
			(effects
				(font
					(size 1.27 1.27)
				)
			)
		)
		(property "Value" ""
			(at 0 0 180)
			(layer "F.Fab")
			(effects
				(font
					(size 1.27 1.27)
				)
			)
		)
		(duplicate_pad_numbers_are_jumpers no)
		(fp_line
			(start 0.7874 0.4064)
			(end -0.7874 0.4064)
			(stroke
				(width 0.1524)
				(type default)
			)
			(layer "F.SilkS")
		)
		(fp_line
			(start 0.7874 -0.4064)
			(end 0.7874 0.4064)
			(stroke
				(width 0.1524)
				(type default)
			)
			(layer "F.SilkS")
		)
		(fp_line
			(start -0.7874 0.4064)
			(end -0.7874 -0.4064)
			(stroke
				(width 0.1524)
				(type default)
			)
			(layer "F.SilkS")
		)
		(fp_line
			(start -0.7874 -0.4064)
			(end 0.7874 -0.4064)
			(stroke
				(width 0.1524)
				(type default)
			)
			(layer "F.SilkS")
		)
		(fp_line
			(start 0.67945 0.3048)
			(end 0.120396 0.3048)
			(stroke
				(width 0.1)
				(type default)
			)
			(layer "F.Fab")
		)
		(fp_line
			(start 0.67945 -0.3048)
			(end 0.67945 0.3048)
			(stroke
				(width 0.1)
				(type default)
			)
			(layer "F.Fab")
		)
		(fp_line
			(start 0.12065 -0.2794)
			(end 0.12065 -0.3048)
			(stroke
				(width 0.1)
				(type default)
			)
			(layer "F.Fab")
		)
		(fp_line
			(start 0.12065 -0.3048)
			(end 0.67945 -0.3048)
			(stroke
				(width 0.1)
				(type default)
			)
			(layer "F.Fab")
		)
		(fp_line
			(start 0.120396 0.3048)
			(end 0.120396 0.2794)
			(stroke
				(width 0.1)
				(type default)
			)
			(layer "F.Fab")
		)
		(fp_line
			(start 0.120396 0.2794)
			(end -0.12065 0.2794)
			(stroke
				(width 0.1)
				(type default)
			)
			(layer "F.Fab")
		)
		(fp_line
			(start -0.12065 0.3048)
			(end -0.67945 0.3048)
			(stroke
				(width 0.1)
				(type default)
			)
			(layer "F.Fab")
		)
		(fp_line
			(start -0.12065 0.2794)
			(end -0.12065 0.3048)
			(stroke
				(width 0.1)
				(type default)
			)
			(layer "F.Fab")
		)
		(fp_line
			(start -0.12065 -0.2794)
			(end 0.12065 -0.2794)
			(stroke
				(width 0.1)
				(type default)
			)
			(layer "F.Fab")
		)
		(fp_line
			(start -0.12065 -0.305054)
			(end -0.12065 -0.2794)
			(stroke
				(width 0.1)
				(type default)
			)
			(layer "F.Fab")
		)
		(fp_line
			(start -0.67945 0.3048)
			(end -0.67945 -0.305054)
			(stroke
				(width 0.1)
				(type default)
			)
			(layer "F.Fab")
		)
		(fp_line
			(start -0.67945 -0.305054)
			(end -0.12065 -0.305054)
			(stroke
				(width 0.1)
				(type default)
			)
			(layer "F.Fab")
		)
		(pad "1" smd circle
			(at -0.40005 0 180)
			(size 0 0)
			(layers "F.Cu" "F.Mask" "F.Paste")
			(net "P12V_AUX")
		)
		(pad "2" smd circle
			(at 0.40005 0 180)
			(size 0 0)
			(layers "F.Cu" "F.Mask" "F.Paste")
			(net "GND")
		)
	)
	(footprint ""
		(layer "F.Cu")
		(at 319.940178 -42.684954)
		(property "Reference" "C2048"
			(at 0 0 0)
			(layer "F.SilkS")
			(hide yes)
			(effects
				(font
					(size 1.27 1.27)
				)
			)
		)
		(property "Value" ""
			(at 0 0 0)
			(layer "F.Fab")
			(effects
				(font
					(size 1.27 1.27)
				)
			)
		)
		(duplicate_pad_numbers_are_jumpers no)
		(fp_line
			(start -0.7874 -0.4064)
			(end 0.7874 -0.4064)
			(stroke
				(width 0.1524)
				(type default)
			)
			(layer "F.SilkS")
		)
		(fp_line
			(start -0.7874 0.4064)
			(end -0.7874 -0.4064)
			(stroke
				(width 0.1524)
				(type default)
			)
			(layer "F.SilkS")
		)
		(fp_line
			(start 0.7874 -0.4064)
			(end 0.7874 0.4064)
			(stroke
				(width 0.1524)
				(type default)
			)
			(layer "F.SilkS")
		)
		(fp_line
			(start 0.7874 0.4064)
			(end -0.7874 0.4064)
			(stroke
				(width 0.1524)
				(type default)
			)
			(layer "F.SilkS")
		)
		(fp_line
			(start -0.67945 -0.305054)
			(end -0.12065 -0.305054)
			(stroke
				(width 0.1)
				(type default)
			)
			(layer "F.Fab")
		)
		(fp_line
			(start -0.67945 0.3048)
			(end -0.67945 -0.305054)
			(stroke
				(width 0.1)
				(type default)
			)
			(layer "F.Fab")
		)
		(fp_line
			(start -0.12065 -0.305054)
			(end -0.12065 -0.2794)
			(stroke
				(width 0.1)
				(type default)
			)
			(layer "F.Fab")
		)
		(fp_line
			(start -0.12065 -0.2794)
			(end 0.12065 -0.2794)
			(stroke
				(width 0.1)
				(type default)
			)
			(layer "F.Fab")
		)
		(fp_line
			(start -0.12065 0.2794)
			(end -0.12065 0.3048)
			(stroke
				(width 0.1)
				(type default)
			)
			(layer "F.Fab")
		)
		(fp_line
			(start -0.12065 0.3048)
			(end -0.67945 0.3048)
			(stroke
				(width 0.1)
				(type default)
			)
			(layer "F.Fab")
		)
		(fp_line
			(start 0.120396 0.2794)
			(end -0.12065 0.2794)
			(stroke
				(width 0.1)
				(type default)
			)
			(layer "F.Fab")
		)
		(fp_line
			(start 0.120396 0.3048)
			(end 0.120396 0.2794)
			(stroke
				(width 0.1)
				(type default)
			)
			(layer "F.Fab")
		)
		(fp_line
			(start 0.12065 -0.3048)
			(end 0.67945 -0.3048)
			(stroke
				(width 0.1)
				(type default)
			)
			(layer "F.Fab")
		)
		(fp_line
			(start 0.12065 -0.2794)
			(end 0.12065 -0.3048)
			(stroke
				(width 0.1)
				(type default)
			)
			(layer "F.Fab")
		)
		(fp_line
			(start 0.67945 -0.3048)
			(end 0.67945 0.3048)
			(stroke
				(width 0.1)
				(type default)
			)
			(layer "F.Fab")
		)
		(fp_line
			(start 0.67945 0.3048)
			(end 0.120396 0.3048)
			(stroke
				(width 0.1)
				(type default)
			)
			(layer "F.Fab")
		)
		(pad "1" smd circle
			(at -0.40005 0)
			(size 0 0)
			(layers "F.Cu" "F.Mask" "F.Paste")
			(net "P3V3_ADC_TIC")
		)
		(pad "2" smd circle
			(at 0.40005 0)
			(size 0 0)
			(layers "F.Cu" "F.Mask" "F.Paste")
			(net "GND")
		)
	)
	(footprint ""
		(layer "F.Cu")
		(at 434.796692 -16.199866 -90)
		(property "Reference" "R1671"
			(at 0 0 270)
			(layer "F.SilkS")
			(hide yes)
			(effects
				(font
					(size 1.27 1.27)
				)
			)
		)
		(property "Value" ""
			(at 0 0 270)
			(layer "F.Fab")
			(effects
				(font
					(size 1.27 1.27)
				)
			)
		)
		(duplicate_pad_numbers_are_jumpers no)
		(fp_line
			(start -0.7874 0.4064)
			(end -0.7874 -0.4064)
			(stroke
				(width 0.1524)
				(type default)
			)
			(layer "F.SilkS")
		)
		(fp_line
			(start 0.7874 0.4064)
			(end -0.7874 0.4064)
			(stroke
				(width 0.1524)
				(type default)
			)
			(layer "F.SilkS")
		)
		(fp_line
			(start -0.7874 -0.4064)
			(end 0.7874 -0.4064)
			(stroke
				(width 0.1524)
				(type default)
			)
			(layer "F.SilkS")
		)
		(fp_line
			(start 0.7874 -0.4064)
			(end 0.7874 0.4064)
			(stroke
				(width 0.1524)
				(type default)
			)
			(layer "F.SilkS")
		)
		(fp_line
			(start -0.67945 0.3048)
			(end -0.67945 -0.305054)
			(stroke
				(width 0.1)
				(type default)
			)
			(layer "F.Fab")
		)
		(fp_line
			(start -0.12065 0.3048)
			(end -0.67945 0.3048)
			(stroke
				(width 0.1)
				(type default)
			)
			(layer "F.Fab")
		)
		(fp_line
			(start 0.120396 0.3048)
			(end 0.120396 0.2794)
			(stroke
				(width 0.1)
				(type default)
			)
			(layer "F.Fab")
		)
		(fp_line
			(start 0.67945 0.3048)
			(end 0.120396 0.3048)
			(stroke
				(width 0.1)
				(type default)
			)
			(layer "F.Fab")
		)
		(fp_line
			(start -0.12065 0.2794)
			(end -0.12065 0.3048)
			(stroke
				(width 0.1)
				(type default)
			)
			(layer "F.Fab")
		)
		(fp_line
			(start 0.120396 0.2794)
			(end -0.12065 0.2794)
			(stroke
				(width 0.1)
				(type default)
			)
			(layer "F.Fab")
		)
		(fp_line
			(start -0.12065 -0.2794)
			(end 0.12065 -0.2794)
			(stroke
				(width 0.1)
				(type default)
			)
			(layer "F.Fab")
		)
		(fp_line
			(start 0.12065 -0.2794)
			(end 0.12065 -0.3048)
			(stroke
				(width 0.1)
				(type default)
			)
			(layer "F.Fab")
		)
		(fp_line
			(start 0.12065 -0.3048)
			(end 0.67945 -0.3048)
			(stroke
				(width 0.1)
				(type default)
			)
			(layer "F.Fab")
		)
		(fp_line
			(start 0.67945 -0.3048)
			(end 0.67945 0.3048)
			(stroke
				(width 0.1)
				(type default)
			)
			(layer "F.Fab")
		)
		(fp_line
			(start -0.67945 -0.305054)
			(end -0.12065 -0.305054)
			(stroke
				(width 0.1)
				(type default)
			)
			(layer "F.Fab")
		)
		(fp_line
			(start -0.12065 -0.305054)
			(end -0.12065 -0.2794)
			(stroke
				(width 0.1)
				(type default)
			)
			(layer "F.Fab")
		)
		(pad "1" smd circle
			(at -0.40005 0 270)
			(size 0 0)
			(layers "F.Cu" "F.Mask" "F.Paste")
			(net "OCP_SFF_AUX_PWR_EN")
		)
		(pad "2" smd circle
			(at 0.40005 0 270)
			(size 0 0)
			(layers "F.Cu" "F.Mask" "F.Paste")
			(net "OCP_SFF_AUX_PWR_EN_R")
		)
	)
	(footprint ""
		(layer "F.Cu")
		(at 391.268458 -402.7424 -90)
		(property "Reference" "R1103"
			(at 0 0 270)
			(layer "F.SilkS")
			(hide yes)
			(effects
				(font
					(size 1.27 1.27)
				)
			)
		)
		(property "Value" ""
			(at 0 0 270)
			(layer "F.Fab")
			(effects
				(font
					(size 1.27 1.27)
				)
			)
		)
		(duplicate_pad_numbers_are_jumpers no)
		(fp_line
			(start -0.32512 0.175006)
			(end -0.32512 -0.175006)
			(stroke
				(width 0.1)
				(type default)
			)
			(layer "F.Fab")
		)
		(fp_line
			(start 0.32512 0.175006)
			(end -0.32512 0.175006)
			(stroke
				(width 0.1)
				(type default)
			)
			(layer "F.Fab")
		)
		(fp_line
			(start -0.32512 -0.175006)
			(end 0.32512 -0.175006)
			(stroke
				(width 0.1)
				(type default)
			)
			(layer "F.Fab")
		)
		(fp_line
			(start 0.32512 -0.175006)
			(end 0.32512 0.175006)
			(stroke
				(width 0.1)
				(type default)
			)
			(layer "F.Fab")
		)
		(pad "1" smd rect
			(at -0.2667 0 270)
			(size 0.3048 0.381)
			(layers "F.Cu" "F.Mask" "F.Paste")
			(net "RST_RT_CPU0_P3_PERST_R_N")
		)
		(pad "2" smd rect
			(at 0.2667 0 90)
			(size 0.3048 0.381)
			(layers "F.Cu" "F.Mask" "F.Paste")
			(net "GND")
		)
	)
	(footprint ""
		(layer "F.Cu")
		(at 325.740776 -387.853428)
		(property "Reference" "C903"
			(at 0 0 0)
			(layer "F.SilkS")
			(hide yes)
			(effects
				(font
					(size 1.27 1.27)
				)
			)
		)
		(property "Value" ""
			(at 0 0 0)
			(layer "F.Fab")
			(effects
				(font
					(size 1.27 1.27)
				)
			)
		)
		(duplicate_pad_numbers_are_jumpers no)
		(fp_line
			(start -0.299974 -0.150114)
			(end 0.299974 -0.150114)
			(stroke
				(width 0.1)
				(type default)
			)
			(layer "F.Fab")
		)
		(fp_line
			(start -0.299974 0.150114)
			(end -0.299974 -0.150114)
			(stroke
				(width 0.1)
				(type default)
			)
			(layer "F.Fab")
		)
		(fp_line
			(start 0.299974 -0.150114)
			(end 0.299974 0.150114)
			(stroke
				(width 0.1)
				(type default)
			)
			(layer "F.Fab")
		)
		(fp_line
			(start 0.299974 0.150114)
			(end -0.299974 0.150114)
			(stroke
				(width 0.1)
				(type default)
			)
			(layer "F.Fab")
		)
		(pad "1" smd rect
			(at -0.2667 0)
			(size 0.3048 0.381)
			(layers "F.Cu" "F.Mask" "F.Paste")
			(net "P5E_CPU0_P0_TX_C_DP<15>")
		)
		(pad "2" smd rect
			(at 0.2667 0)
			(size 0.3048 0.381)
			(layers "F.Cu" "F.Mask" "F.Paste")
			(net "P5E_CPU0_P0_TX_DP<15>")
		)
	)
	(footprint ""
		(layer "F.Cu")
		(at 323.637148 -46.986698)
		(property "Reference" "R3679"
			(at 0 0 0)
			(layer "F.SilkS")
			(hide yes)
			(effects
				(font
					(size 1.27 1.27)
				)
			)
		)
		(property "Value" ""
			(at 0 0 0)
			(layer "F.Fab")
			(effects
				(font
					(size 1.27 1.27)
				)
			)
		)
		(duplicate_pad_numbers_are_jumpers no)
		(fp_line
			(start -0.7874 -0.4064)
			(end 0.7874 -0.4064)
			(stroke
				(width 0.1524)
				(type default)
			)
			(layer "F.SilkS")
		)
		(fp_line
			(start -0.7874 0.4064)
			(end -0.7874 -0.4064)
			(stroke
				(width 0.1524)
				(type default)
			)
			(layer "F.SilkS")
		)
		(fp_line
			(start 0.7874 -0.4064)
			(end 0.7874 0.4064)
			(stroke
				(width 0.1524)
				(type default)
			)
			(layer "F.SilkS")
		)
		(fp_line
			(start 0.7874 0.4064)
			(end -0.7874 0.4064)
			(stroke
				(width 0.1524)
				(type default)
			)
			(layer "F.SilkS")
		)
		(fp_line
			(start -0.67945 -0.305054)
			(end -0.12065 -0.305054)
			(stroke
				(width 0.1)
				(type default)
			)
			(layer "F.Fab")
		)
		(fp_line
			(start -0.67945 0.3048)
			(end -0.67945 -0.305054)
			(stroke
				(width 0.1)
				(type default)
			)
			(layer "F.Fab")
		)
		(fp_line
			(start -0.12065 -0.305054)
			(end -0.12065 -0.2794)
			(stroke
				(width 0.1)
				(type default)
			)
			(layer "F.Fab")
		)
		(fp_line
			(start -0.12065 -0.2794)
			(end 0.12065 -0.2794)
			(stroke
				(width 0.1)
				(type default)
			)
			(layer "F.Fab")
		)
		(fp_line
			(start -0.12065 0.2794)
			(end -0.12065 0.3048)
			(stroke
				(width 0.1)
				(type default)
			)
			(layer "F.Fab")
		)
		(fp_line
			(start -0.12065 0.3048)
			(end -0.67945 0.3048)
			(stroke
				(width 0.1)
				(type default)
			)
			(layer "F.Fab")
		)
		(fp_line
			(start 0.120396 0.2794)
			(end -0.12065 0.2794)
			(stroke
				(width 0.1)
				(type default)
			)
			(layer "F.Fab")
		)
		(fp_line
			(start 0.120396 0.3048)
			(end 0.120396 0.2794)
			(stroke
				(width 0.1)
				(type default)
			)
			(layer "F.Fab")
		)
		(fp_line
			(start 0.12065 -0.3048)
			(end 0.67945 -0.3048)
			(stroke
				(width 0.1)
				(type default)
			)
			(layer "F.Fab")
		)
		(fp_line
			(start 0.12065 -0.2794)
			(end 0.12065 -0.3048)
			(stroke
				(width 0.1)
				(type default)
			)
			(layer "F.Fab")
		)
		(fp_line
			(start 0.67945 -0.3048)
			(end 0.67945 0.3048)
			(stroke
				(width 0.1)
				(type default)
			)
			(layer "F.Fab")
		)
		(fp_line
			(start 0.67945 0.3048)
			(end 0.120396 0.3048)
			(stroke
				(width 0.1)
				(type default)
			)
			(layer "F.Fab")
		)
		(pad "1" smd rect
			(at -0.40005 0 180)
			(size 0.4572 0.508)
			(layers "F.Cu" "F.Mask" "F.Paste")
			(net "P12V_AUX_ADC")
		)
		(pad "2" smd rect
			(at 0.40005 0 180)
			(size 0.4572 0.508)
			(layers "F.Cu" "F.Mask" "F.Paste")
			(net "P12V_AUX_ADC_MAM")
		)
	)
	(footprint ""
		(layer "F.Cu")
		(at 49.849532 -343.716864 180)
		(property "Reference" "PC174"
			(at 0 0 180)
			(layer "F.SilkS")
			(hide yes)
			(effects
				(font
					(size 1.27 1.27)
				)
			)
		)
		(property "Value" ""
			(at 0 0 180)
			(layer "F.Fab")
			(effects
				(font
					(size 1.27 1.27)
				)
			)
		)
		(duplicate_pad_numbers_are_jumpers no)
		(fp_line
			(start 0.7874 0.4064)
			(end -0.7874 0.4064)
			(stroke
				(width 0.1524)
				(type default)
			)
			(layer "F.SilkS")
		)
		(fp_line
			(start 0.7874 -0.4064)
			(end 0.7874 0.4064)
			(stroke
				(width 0.1524)
				(type default)
			)
			(layer "F.SilkS")
		)
		(fp_line
			(start -0.7874 0.4064)
			(end -0.7874 -0.4064)
			(stroke
				(width 0.1524)
				(type default)
			)
			(layer "F.SilkS")
		)
		(fp_line
			(start -0.7874 -0.4064)
			(end 0.7874 -0.4064)
			(stroke
				(width 0.1524)
				(type default)
			)
			(layer "F.SilkS")
		)
		(fp_line
			(start 0.67945 0.3048)
			(end 0.120396 0.3048)
			(stroke
				(width 0.1)
				(type default)
			)
			(layer "F.Fab")
		)
		(fp_line
			(start 0.67945 -0.3048)
			(end 0.67945 0.3048)
			(stroke
				(width 0.1)
				(type default)
			)
			(layer "F.Fab")
		)
		(fp_line
			(start 0.12065 -0.2794)
			(end 0.12065 -0.3048)
			(stroke
				(width 0.1)
				(type default)
			)
			(layer "F.Fab")
		)
		(fp_line
			(start 0.12065 -0.3048)
			(end 0.67945 -0.3048)
			(stroke
				(width 0.1)
				(type default)
			)
			(layer "F.Fab")
		)
		(fp_line
			(start 0.120396 0.3048)
			(end 0.120396 0.2794)
			(stroke
				(width 0.1)
				(type default)
			)
			(layer "F.Fab")
		)
		(fp_line
			(start 0.120396 0.2794)
			(end -0.12065 0.2794)
			(stroke
				(width 0.1)
				(type default)
			)
			(layer "F.Fab")
		)
		(fp_line
			(start -0.12065 0.3048)
			(end -0.67945 0.3048)
			(stroke
				(width 0.1)
				(type default)
			)
			(layer "F.Fab")
		)
		(fp_line
			(start -0.12065 0.2794)
			(end -0.12065 0.3048)
			(stroke
				(width 0.1)
				(type default)
			)
			(layer "F.Fab")
		)
		(fp_line
			(start -0.12065 -0.2794)
			(end 0.12065 -0.2794)
			(stroke
				(width 0.1)
				(type default)
			)
			(layer "F.Fab")
		)
		(fp_line
			(start -0.12065 -0.305054)
			(end -0.12065 -0.2794)
			(stroke
				(width 0.1)
				(type default)
			)
			(layer "F.Fab")
		)
		(fp_line
			(start -0.67945 0.3048)
			(end -0.67945 -0.305054)
			(stroke
				(width 0.1)
				(type default)
			)
			(layer "F.Fab")
		)
		(fp_line
			(start -0.67945 -0.305054)
			(end -0.12065 -0.305054)
			(stroke
				(width 0.1)
				(type default)
			)
			(layer "F.Fab")
		)
		(pad "1" smd circle
			(at -0.40005 0 180)
			(size 0 0)
			(layers "F.Cu" "F.Mask" "F.Paste")
			(net "SW_PVDDIO_P1_SW1")
		)
		(pad "2" smd circle
			(at 0.40005 0 180)
			(size 0 0)
			(layers "F.Cu" "F.Mask" "F.Paste")
			(net "SW_PVDDIO_P1_SW1_RC")
		)
	)
)
